(kicad_pcb
	(version 20260206)
	(generator "pcbnew")
	(generator_version "10.0")
	(general
		(thickness 1.6)
		(legacy_teardrops no)
	)
	(paper "A4")
	(title_block
		(title "01162023_DA0F0TEBIF0_F0T_Expander_BD_F_brd_V02_OCP.brd")
		(comment 1 "Grand Teton / footprints 8519-8526 of 9728")
	)
	(layers
		(0 "F.Cu" signal "TOP")
		(4 "In1.Cu" signal "GND")
		(6 "In2.Cu" signal "VCC")
		(8 "In3.Cu" signal "VCC1")
		(10 "In4.Cu" signal "GND1")
		(12 "In5.Cu" signal "IN1")
		(14 "In6.Cu" signal "GND2")
		(16 "In7.Cu" signal "IN2")
		(18 "In8.Cu" signal "GND3")
		(20 "In9.Cu" signal "IN3")
		(22 "In10.Cu" signal "GND4")
		(24 "In11.Cu" signal "IN4")
		(26 "In12.Cu" signal "GND5")
		(28 "In13.Cu" signal "IN5")
		(30 "In14.Cu" signal "GND6")
		(32 "In15.Cu" signal "IN6")
		(34 "In16.Cu" signal "GND7")
		(2 "B.Cu" signal "BOTTOM")
		(9 "F.Adhes" user "F.Adhesive")
		(11 "B.Adhes" user "B.Adhesive")
		(13 "F.Paste" user "Package Geometry/Pastemask Top")
		(15 "B.Paste" user "Package Geometry/Pastemask Bottom")
		(5 "F.SilkS" user "Ref Des/Silkscreen Top")
		(7 "B.SilkS" user "Ref Des/Silkscreen Bottom")
		(1 "F.Mask" user "Board Geometry/Soldermask Top")
		(3 "B.Mask" user "Board Geometry/Soldermask Bottom")
		(17 "Dwgs.User" user "User.Drawings")
		(19 "Cmts.User" user "User.Comments")
		(21 "Eco1.User" user "User.Eco1")
		(23 "Eco2.User" user "User.Eco2")
		(25 "Edge.Cuts" user "Board Geometry/Outline")
		(27 "Margin" user)
		(31 "F.CrtYd" user "Package Geometry/Place Bound Top")
		(29 "B.CrtYd" user "Package Geometry/Place Bound Bottom")
		(35 "F.Fab" user "Ref Des/Assembly Top")
		(33 "B.Fab" user "Ref Des/Assembly Bottom")
	)
	(footprint ""
		(layer "B.Cu")
		(at 126.179072 -308.580028 90)
		(property "Reference" "C4261"
			(at 0 0 90)
			(layer "B.SilkS")
			(hide yes)
			(effects
				(font
					(size 1.27 1.27)
				)
				(justify mirror)
			)
		)
		(property "Value" ""
			(at 0 0 90)
			(layer "B.Fab")
			(effects
				(font
					(size 1.27 1.27)
				)
				(justify mirror)
			)
		)
		(duplicate_pad_numbers_are_jumpers no)
		(fp_line
			(start 1.2954 -0.5842)
			(end -1.2954 -0.5842)
			(stroke
				(width 0.1524)
				(type default)
			)
			(layer "B.SilkS")
		)
		(fp_line
			(start -1.2954 -0.5842)
			(end -1.2954 0.5842)
			(stroke
				(width 0.1524)
				(type default)
			)
			(layer "B.SilkS")
		)
		(fp_line
			(start 1.2954 0.5842)
			(end 1.2954 -0.5842)
			(stroke
				(width 0.1524)
				(type default)
			)
			(layer "B.SilkS")
		)
		(fp_line
			(start -1.2954 0.5842)
			(end 1.2954 0.5842)
			(stroke
				(width 0.1524)
				(type default)
			)
			(layer "B.SilkS")
		)
		(fp_line
			(start 0.8636 -0.4572)
			(end -0.8636 -0.4572)
			(stroke
				(width 0.1)
				(type default)
			)
			(layer "B.Fab")
		)
		(fp_line
			(start -0.8636 -0.4572)
			(end -0.8636 -0.4064)
			(stroke
				(width 0.1)
				(type default)
			)
			(layer "B.Fab")
		)
		(fp_line
			(start 1.1938 -0.4064)
			(end 0.8636 -0.4064)
			(stroke
				(width 0.1)
				(type default)
			)
			(layer "B.Fab")
		)
		(fp_line
			(start 0.8636 -0.4064)
			(end 0.8636 -0.4572)
			(stroke
				(width 0.1)
				(type default)
			)
			(layer "B.Fab")
		)
		(fp_line
			(start -0.8636 -0.4064)
			(end -1.1938 -0.4064)
			(stroke
				(width 0.1)
				(type default)
			)
			(layer "B.Fab")
		)
		(fp_line
			(start -1.1938 -0.4064)
			(end -1.1938 0.4064)
			(stroke
				(width 0.1)
				(type default)
			)
			(layer "B.Fab")
		)
		(fp_line
			(start 1.1938 0.4064)
			(end 1.1938 -0.4064)
			(stroke
				(width 0.1)
				(type default)
			)
			(layer "B.Fab")
		)
		(fp_line
			(start 0.8636 0.4064)
			(end 1.1938 0.4064)
			(stroke
				(width 0.1)
				(type default)
			)
			(layer "B.Fab")
		)
		(fp_line
			(start -0.8636 0.4064)
			(end -0.8636 0.4572)
			(stroke
				(width 0.1)
				(type default)
			)
			(layer "B.Fab")
		)
		(fp_line
			(start -1.1938 0.4064)
			(end -0.8636 0.4064)
			(stroke
				(width 0.1)
				(type default)
			)
			(layer "B.Fab")
		)
		(fp_line
			(start 0.8636 0.4572)
			(end 0.8636 0.4064)
			(stroke
				(width 0.1)
				(type default)
			)
			(layer "B.Fab")
		)
		(fp_line
			(start -0.8636 0.4572)
			(end 0.8636 0.4572)
			(stroke
				(width 0.1)
				(type default)
			)
			(layer "B.Fab")
		)
		(pad "1" smd rect
			(at 0.7366 0)
			(size 0.7112 0.8128)
			(layers "B.Cu" "B.Mask" "B.Paste")
			(net "P0V8_PEX1")
		)
		(pad "2" smd rect
			(at -0.7366 0)
			(size 0.7112 0.8128)
			(layers "B.Cu" "B.Mask" "B.Paste")
			(net "GND")
		)
	)
	(footprint ""
		(layer "B.Cu")
		(at 44.449746 -295.89984)
		(property "Reference" "C3000"
			(at 0 0 0)
			(layer "B.SilkS")
			(hide yes)
			(effects
				(font
					(size 1.27 1.27)
				)
				(justify mirror)
			)
		)
		(property "Value" ""
			(at 0 0 0)
			(layer "B.Fab")
			(effects
				(font
					(size 1.27 1.27)
				)
				(justify mirror)
			)
		)
		(duplicate_pad_numbers_are_jumpers no)
		(fp_line
			(start -0.299974 -0.150114)
			(end -0.299974 0.150114)
			(stroke
				(width 0.1)
				(type default)
			)
			(layer "B.Fab")
		)
		(fp_line
			(start -0.299974 0.150114)
			(end 0.299974 0.150114)
			(stroke
				(width 0.1)
				(type default)
			)
			(layer "B.Fab")
		)
		(fp_line
			(start 0.299974 -0.150114)
			(end -0.299974 -0.150114)
			(stroke
				(width 0.1)
				(type default)
			)
			(layer "B.Fab")
		)
		(fp_line
			(start 0.299974 0.150114)
			(end 0.299974 -0.150114)
			(stroke
				(width 0.1)
				(type default)
			)
			(layer "B.Fab")
		)
		(pad "1" smd rect
			(at 0.2667 0 180)
			(size 0.3048 0.381)
			(layers "B.Cu" "B.Mask" "B.Paste")
			(net "P1V8_PEX")
		)
		(pad "2" smd rect
			(at -0.2667 0 180)
			(size 0.3048 0.381)
			(layers "B.Cu" "B.Mask" "B.Paste")
			(net "GND")
		)
	)
	(footprint ""
		(layer "B.Cu")
		(at 389.89 -242.189 -90)
		(property "Reference" "C2572"
			(at 0 0 90)
			(layer "B.SilkS")
			(hide yes)
			(effects
				(font
					(size 1.27 1.27)
				)
				(justify mirror)
			)
		)
		(property "Value" ""
			(at 0 0 90)
			(layer "B.Fab")
			(effects
				(font
					(size 1.27 1.27)
				)
				(justify mirror)
			)
		)
		(duplicate_pad_numbers_are_jumpers no)
		(fp_line
			(start -0.7874 0.4064)
			(end 0.7874 0.4064)
			(stroke
				(width 0.1524)
				(type default)
			)
			(layer "B.SilkS")
		)
		(fp_line
			(start 0.7874 0.4064)
			(end 0.7874 -0.4064)
			(stroke
				(width 0.1524)
				(type default)
			)
			(layer "B.SilkS")
		)
		(fp_line
			(start -0.7874 -0.4064)
			(end -0.7874 0.4064)
			(stroke
				(width 0.1524)
				(type default)
			)
			(layer "B.SilkS")
		)
		(fp_line
			(start 0.7874 -0.4064)
			(end -0.7874 -0.4064)
			(stroke
				(width 0.1524)
				(type default)
			)
			(layer "B.SilkS")
		)
		(fp_line
			(start -0.67945 0.3048)
			(end -0.120396 0.3048)
			(stroke
				(width 0.1)
				(type default)
			)
			(layer "B.Fab")
		)
		(fp_line
			(start -0.120396 0.3048)
			(end -0.120396 0.2794)
			(stroke
				(width 0.1)
				(type default)
			)
			(layer "B.Fab")
		)
		(fp_line
			(start 0.12065 0.3048)
			(end 0.67945 0.3048)
			(stroke
				(width 0.1)
				(type default)
			)
			(layer "B.Fab")
		)
		(fp_line
			(start 0.67945 0.3048)
			(end 0.67945 -0.305054)
			(stroke
				(width 0.1)
				(type default)
			)
			(layer "B.Fab")
		)
		(fp_line
			(start -0.120396 0.2794)
			(end 0.12065 0.2794)
			(stroke
				(width 0.1)
				(type default)
			)
			(layer "B.Fab")
		)
		(fp_line
			(start 0.12065 0.2794)
			(end 0.12065 0.3048)
			(stroke
				(width 0.1)
				(type default)
			)
			(layer "B.Fab")
		)
		(fp_line
			(start -0.12065 -0.2794)
			(end -0.12065 -0.3048)
			(stroke
				(width 0.1)
				(type default)
			)
			(layer "B.Fab")
		)
		(fp_line
			(start 0.12065 -0.2794)
			(end -0.12065 -0.2794)
			(stroke
				(width 0.1)
				(type default)
			)
			(layer "B.Fab")
		)
		(fp_line
			(start -0.67945 -0.3048)
			(end -0.67945 0.3048)
			(stroke
				(width 0.1)
				(type default)
			)
			(layer "B.Fab")
		)
		(fp_line
			(start -0.12065 -0.3048)
			(end -0.67945 -0.3048)
			(stroke
				(width 0.1)
				(type default)
			)
			(layer "B.Fab")
		)
		(fp_line
			(start 0.12065 -0.305054)
			(end 0.12065 -0.2794)
			(stroke
				(width 0.1)
				(type default)
			)
			(layer "B.Fab")
		)
		(fp_line
			(start 0.67945 -0.305054)
			(end 0.12065 -0.305054)
			(stroke
				(width 0.1)
				(type default)
			)
			(layer "B.Fab")
		)
		(pad "1" smd circle
			(at 0.40005 0 90)
			(size 0 0)
			(layers "B.Cu" "B.Mask" "B.Paste")
			(net "P3V3_AUX")
		)
		(pad "2" smd circle
			(at -0.40005 0 90)
			(size 0 0)
			(layers "B.Cu" "B.Mask" "B.Paste")
			(net "GND")
		)
	)
	(footprint ""
		(layer "B.Cu")
		(at 234.514644 -231.225598 -90)
		(property "Reference" "R4517"
			(at 0 0 90)
			(layer "B.SilkS")
			(hide yes)
			(effects
				(font
					(size 1.27 1.27)
				)
				(justify mirror)
			)
		)
		(property "Value" ""
			(at 0 0 90)
			(layer "B.Fab")
			(effects
				(font
					(size 1.27 1.27)
				)
				(justify mirror)
			)
		)
		(duplicate_pad_numbers_are_jumpers no)
		(fp_line
			(start -0.7874 0.4064)
			(end 0.7874 0.4064)
			(stroke
				(width 0.1524)
				(type default)
			)
			(layer "B.SilkS")
		)
		(fp_line
			(start 0.7874 0.4064)
			(end 0.7874 -0.4064)
			(stroke
				(width 0.1524)
				(type default)
			)
			(layer "B.SilkS")
		)
		(fp_line
			(start -0.7874 -0.4064)
			(end -0.7874 0.4064)
			(stroke
				(width 0.1524)
				(type default)
			)
			(layer "B.SilkS")
		)
		(fp_line
			(start 0.7874 -0.4064)
			(end -0.7874 -0.4064)
			(stroke
				(width 0.1524)
				(type default)
			)
			(layer "B.SilkS")
		)
		(fp_line
			(start -0.67945 0.3048)
			(end -0.120396 0.3048)
			(stroke
				(width 0.1)
				(type default)
			)
			(layer "B.Fab")
		)
		(fp_line
			(start -0.120396 0.3048)
			(end -0.120396 0.2794)
			(stroke
				(width 0.1)
				(type default)
			)
			(layer "B.Fab")
		)
		(fp_line
			(start 0.12065 0.3048)
			(end 0.67945 0.3048)
			(stroke
				(width 0.1)
				(type default)
			)
			(layer "B.Fab")
		)
		(fp_line
			(start 0.67945 0.3048)
			(end 0.67945 -0.305054)
			(stroke
				(width 0.1)
				(type default)
			)
			(layer "B.Fab")
		)
		(fp_line
			(start -0.120396 0.2794)
			(end 0.12065 0.2794)
			(stroke
				(width 0.1)
				(type default)
			)
			(layer "B.Fab")
		)
		(fp_line
			(start 0.12065 0.2794)
			(end 0.12065 0.3048)
			(stroke
				(width 0.1)
				(type default)
			)
			(layer "B.Fab")
		)
		(fp_line
			(start -0.12065 -0.2794)
			(end -0.12065 -0.3048)
			(stroke
				(width 0.1)
				(type default)
			)
			(layer "B.Fab")
		)
		(fp_line
			(start 0.12065 -0.2794)
			(end -0.12065 -0.2794)
			(stroke
				(width 0.1)
				(type default)
			)
			(layer "B.Fab")
		)
		(fp_line
			(start -0.67945 -0.3048)
			(end -0.67945 0.3048)
			(stroke
				(width 0.1)
				(type default)
			)
			(layer "B.Fab")
		)
		(fp_line
			(start -0.12065 -0.3048)
			(end -0.67945 -0.3048)
			(stroke
				(width 0.1)
				(type default)
			)
			(layer "B.Fab")
		)
		(fp_line
			(start 0.12065 -0.305054)
			(end 0.12065 -0.2794)
			(stroke
				(width 0.1)
				(type default)
			)
			(layer "B.Fab")
		)
		(fp_line
			(start 0.67945 -0.305054)
			(end 0.12065 -0.305054)
			(stroke
				(width 0.1)
				(type default)
			)
			(layer "B.Fab")
		)
		(pad "1" smd circle
			(at 0.40005 0 90)
			(size 0 0)
			(layers "B.Cu" "B.Mask" "B.Paste")
			(net "SSD3_PWRDIS_BIC")
		)
		(pad "2" smd circle
			(at -0.40005 0 90)
			(size 0 0)
			(layers "B.Cu" "B.Mask" "B.Paste")
			(net "SSD3_PWRDIS_BIC_R")
		)
	)
	(footprint ""
		(layer "B.Cu")
		(at 455.090276 -278.289766 180)
		(property "Reference" "C4400"
			(at 0 0 0)
			(layer "B.SilkS")
			(hide yes)
			(effects
				(font
					(size 1.27 1.27)
				)
				(justify mirror)
			)
		)
		(property "Value" ""
			(at 0 0 0)
			(layer "B.Fab")
			(effects
				(font
					(size 1.27 1.27)
				)
				(justify mirror)
			)
		)
		(duplicate_pad_numbers_are_jumpers no)
		(fp_line
			(start 1.2954 0.5842)
			(end 1.2954 -0.5842)
			(stroke
				(width 0.1524)
				(type default)
			)
			(layer "B.SilkS")
		)
		(fp_line
			(start 1.2954 -0.5842)
			(end -1.2954 -0.5842)
			(stroke
				(width 0.1524)
				(type default)
			)
			(layer "B.SilkS")
		)
		(fp_line
			(start -1.2954 0.5842)
			(end 1.2954 0.5842)
			(stroke
				(width 0.1524)
				(type default)
			)
			(layer "B.SilkS")
		)
		(fp_line
			(start -1.2954 -0.5842)
			(end -1.2954 0.5842)
			(stroke
				(width 0.1524)
				(type default)
			)
			(layer "B.SilkS")
		)
		(fp_line
			(start 1.1938 0.4064)
			(end 1.1938 -0.4064)
			(stroke
				(width 0.1)
				(type default)
			)
			(layer "B.Fab")
		)
		(fp_line
			(start 1.1938 -0.4064)
			(end 0.8636 -0.4064)
			(stroke
				(width 0.1)
				(type default)
			)
			(layer "B.Fab")
		)
		(fp_line
			(start 0.8636 0.4572)
			(end 0.8636 0.4064)
			(stroke
				(width 0.1)
				(type default)
			)
			(layer "B.Fab")
		)
		(fp_line
			(start 0.8636 0.4064)
			(end 1.1938 0.4064)
			(stroke
				(width 0.1)
				(type default)
			)
			(layer "B.Fab")
		)
		(fp_line
			(start 0.8636 -0.4064)
			(end 0.8636 -0.4572)
			(stroke
				(width 0.1)
				(type default)
			)
			(layer "B.Fab")
		)
		(fp_line
			(start 0.8636 -0.4572)
			(end -0.8636 -0.4572)
			(stroke
				(width 0.1)
				(type default)
			)
			(layer "B.Fab")
		)
		(fp_line
			(start -0.8636 0.4572)
			(end 0.8636 0.4572)
			(stroke
				(width 0.1)
				(type default)
			)
			(layer "B.Fab")
		)
		(fp_line
			(start -0.8636 0.4064)
			(end -0.8636 0.4572)
			(stroke
				(width 0.1)
				(type default)
			)
			(layer "B.Fab")
		)
		(fp_line
			(start -0.8636 -0.4064)
			(end -1.1938 -0.4064)
			(stroke
				(width 0.1)
				(type default)
			)
			(layer "B.Fab")
		)
		(fp_line
			(start -0.8636 -0.4572)
			(end -0.8636 -0.4064)
			(stroke
				(width 0.1)
				(type default)
			)
			(layer "B.Fab")
		)
		(fp_line
			(start -1.1938 0.4064)
			(end -0.8636 0.4064)
			(stroke
				(width 0.1)
				(type default)
			)
			(layer "B.Fab")
		)
		(fp_line
			(start -1.1938 -0.4064)
			(end -1.1938 0.4064)
			(stroke
				(width 0.1)
				(type default)
			)
			(layer "B.Fab")
		)
		(pad "1" smd rect
			(at 0.7366 0 90)
			(size 0.7112 0.8128)
			(layers "B.Cu" "B.Mask" "B.Paste")
			(net "P1V25_PEX3")
		)
		(pad "2" smd rect
			(at -0.7366 0 90)
			(size 0.7112 0.8128)
			(layers "B.Cu" "B.Mask" "B.Paste")
			(net "GND")
		)
	)
	(footprint ""
		(layer "B.Cu")
		(at 174.800006 -303.499774 -90)
		(property "Reference" "C3117"
			(at 0 0 90)
			(layer "B.SilkS")
			(hide yes)
			(effects
				(font
					(size 1.27 1.27)
				)
				(justify mirror)
			)
		)
		(property "Value" ""
			(at 0 0 90)
			(layer "B.Fab")
			(effects
				(font
					(size 1.27 1.27)
				)
				(justify mirror)
			)
		)
		(duplicate_pad_numbers_are_jumpers no)
		(fp_line
			(start -0.299974 0.150114)
			(end 0.299974 0.150114)
			(stroke
				(width 0.1)
				(type default)
			)
			(layer "B.Fab")
		)
		(fp_line
			(start 0.299974 0.150114)
			(end 0.299974 -0.150114)
			(stroke
				(width 0.1)
				(type default)
			)
			(layer "B.Fab")
		)
		(fp_line
			(start -0.299974 -0.150114)
			(end -0.299974 0.150114)
			(stroke
				(width 0.1)
				(type default)
			)
			(layer "B.Fab")
		)
		(fp_line
			(start 0.299974 -0.150114)
			(end -0.299974 -0.150114)
			(stroke
				(width 0.1)
				(type default)
			)
			(layer "B.Fab")
		)
		(pad "1" smd rect
			(at 0.2667 0 90)
			(size 0.3048 0.381)
			(layers "B.Cu" "B.Mask" "B.Paste")
			(net "P1V25_PEX1")
		)
		(pad "2" smd rect
			(at -0.2667 0 90)
			(size 0.3048 0.381)
			(layers "B.Cu" "B.Mask" "B.Paste")
			(net "GND")
		)
	)
	(footprint ""
		(layer "B.Cu")
		(at 348.869 -207.772 90)
		(property "Reference" "R2966"
			(at 0 0 90)
			(layer "B.SilkS")
			(hide yes)
			(effects
				(font
					(size 1.27 1.27)
				)
				(justify mirror)
			)
		)
		(property "Value" ""
			(at 0 0 90)
			(layer "B.Fab")
			(effects
				(font
					(size 1.27 1.27)
				)
				(justify mirror)
			)
		)
		(duplicate_pad_numbers_are_jumpers no)
		(fp_line
			(start 0.7874 -0.4064)
			(end -0.7874 -0.4064)
			(stroke
				(width 0.1524)
				(type default)
			)
			(layer "B.SilkS")
		)
		(fp_line
			(start -0.7874 -0.4064)
			(end -0.7874 0.4064)
			(stroke
				(width 0.1524)
				(type default)
			)
			(layer "B.SilkS")
		)
		(fp_line
			(start 0.7874 0.4064)
			(end 0.7874 -0.4064)
			(stroke
				(width 0.1524)
				(type default)
			)
			(layer "B.SilkS")
		)
		(fp_line
			(start -0.7874 0.4064)
			(end 0.7874 0.4064)
			(stroke
				(width 0.1524)
				(type default)
			)
			(layer "B.SilkS")
		)
		(fp_line
			(start 0.67945 -0.305054)
			(end 0.12065 -0.305054)
			(stroke
				(width 0.1)
				(type default)
			)
			(layer "B.Fab")
		)
		(fp_line
			(start 0.12065 -0.305054)
			(end 0.12065 -0.2794)
			(stroke
				(width 0.1)
				(type default)
			)
			(layer "B.Fab")
		)
		(fp_line
			(start -0.12065 -0.3048)
			(end -0.67945 -0.3048)
			(stroke
				(width 0.1)
				(type default)
			)
			(layer "B.Fab")
		)
		(fp_line
			(start -0.67945 -0.3048)
			(end -0.67945 0.3048)
			(stroke
				(width 0.1)
				(type default)
			)
			(layer "B.Fab")
		)
		(fp_line
			(start 0.12065 -0.2794)
			(end -0.12065 -0.2794)
			(stroke
				(width 0.1)
				(type default)
			)
			(layer "B.Fab")
		)
		(fp_line
			(start -0.12065 -0.2794)
			(end -0.12065 -0.3048)
			(stroke
				(width 0.1)
				(type default)
			)
			(layer "B.Fab")
		)
		(fp_line
			(start 0.12065 0.2794)
			(end 0.12065 0.3048)
			(stroke
				(width 0.1)
				(type default)
			)
			(layer "B.Fab")
		)
		(fp_line
			(start -0.120396 0.2794)
			(end 0.12065 0.2794)
			(stroke
				(width 0.1)
				(type default)
			)
			(layer "B.Fab")
		)
		(fp_line
			(start 0.67945 0.3048)
			(end 0.67945 -0.305054)
			(stroke
				(width 0.1)
				(type default)
			)
			(layer "B.Fab")
		)
		(fp_line
			(start 0.12065 0.3048)
			(end 0.67945 0.3048)
			(stroke
				(width 0.1)
				(type default)
			)
			(layer "B.Fab")
		)
		(fp_line
			(start -0.120396 0.3048)
			(end -0.120396 0.2794)
			(stroke
				(width 0.1)
				(type default)
			)
			(layer "B.Fab")
		)
		(fp_line
			(start -0.67945 0.3048)
			(end -0.120396 0.3048)
			(stroke
				(width 0.1)
				(type default)
			)
			(layer "B.Fab")
		)
		(pad "1" smd circle
			(at 0.40005 0 270)
			(size 0 0)
			(layers "B.Cu" "B.Mask" "B.Paste")
			(net "RST_FPGA_BIC_N")
		)
		(pad "2" smd circle
			(at -0.40005 0 270)
			(size 0 0)
			(layers "B.Cu" "B.Mask" "B.Paste")
			(net "RST_FPGA_BIC_R_N")
		)
	)
	(footprint ""
		(layer "B.Cu")
		(at 53.42001 -305.399948 -90)
		(property "Reference" "C2986"
			(at 0 0 90)
			(layer "B.SilkS")
			(hide yes)
			(effects
				(font
					(size 1.27 1.27)
				)
				(justify mirror)
			)
		)
		(property "Value" ""
			(at 0 0 90)
			(layer "B.Fab")
			(effects
				(font
					(size 1.27 1.27)
				)
				(justify mirror)
			)
		)
		(duplicate_pad_numbers_are_jumpers no)
		(fp_line
			(start -0.299974 0.150114)
			(end 0.299974 0.150114)
			(stroke
				(width 0.1)
				(type default)
			)
			(layer "B.Fab")
		)
		(fp_line
			(start 0.299974 0.150114)
			(end 0.299974 -0.150114)
			(stroke
				(width 0.1)
				(type default)
			)
			(layer "B.Fab")
		)
		(fp_line
			(start -0.299974 -0.150114)
			(end -0.299974 0.150114)
			(stroke
				(width 0.1)
				(type default)
			)
			(layer "B.Fab")
		)
		(fp_line
			(start 0.299974 -0.150114)
			(end -0.299974 -0.150114)
			(stroke
				(width 0.1)
				(type default)
			)
			(layer "B.Fab")
		)
		(pad "1" smd rect
			(at 0.2667 0 90)
			(size 0.3048 0.381)
			(layers "B.Cu" "B.Mask" "B.Paste")
			(net "P1V25_SERDES_VDDPLL_PEX0")
		)
		(pad "2" smd rect
			(at -0.2667 0 90)
			(size 0.3048 0.381)
			(layers "B.Cu" "B.Mask" "B.Paste")
			(net "GND")
		)
	)
)
